# S9S_MB_2U (Grand Teton) — schematic netlist excerpt (pin names and nets, part order shuffled) for the footprints in the layout excerpt that follows; sources: Cadence DE-HDL packaged netlist, KiCad conversion of 03242023_DA0F0TMBIJ0_F0T_Motherboard_J_brd_V01_OCP.brd

C547  Q_CAP  1UF 25V 10% X6S  pkg C0402  page 131 : A = P1V05_PCH_AUX ; B = GND
R3058  Q_RES  33.2 1% CHIP  pkg 0402LF  page 241 : A = SMB_SML0_3V3AUX_SCL ; B = SMB_SML0_ME_SCL

(kicad_pcb
	(version 20260206)
	(generator "pcbnew")
	(generator_version "10.0")
	(general
		(thickness 1.6)
		(legacy_teardrops no)
	)
	(paper "A4")
	(title_block
		(title "03242023_DA0F0TMBIJ0_F0T_Motherboard_J_brd_V01_OCP.brd")
		(comment 1 "Grand Teton / footprints 1642-1643 of 6105")
	)
	(layers
		(0 "F.Cu" signal "TOP")
		(4 "In1.Cu" signal "GND")
		(6 "In2.Cu" signal "IN1")
		(8 "In3.Cu" signal "GND1")
		(10 "In4.Cu" signal "IN2")
		(12 "In5.Cu" signal "GND2")
		(14 "In6.Cu" signal "IN3")
		(16 "In7.Cu" signal "GND3")
		(18 "In8.Cu" signal "VCC")
		(20 "In9.Cu" signal "VCC1")
		(22 "In10.Cu" signal "GND4")
		(24 "In11.Cu" signal "IN4")
		(26 "In12.Cu" signal "GND5")
		(28 "In13.Cu" signal "IN5")
		(30 "In14.Cu" signal "GND6")
		(32 "In15.Cu" signal "IN6")
		(34 "In16.Cu" signal "GND7")
		(2 "B.Cu" signal "BOTTOM")
		(9 "F.Adhes" user "F.Adhesive")
		(11 "B.Adhes" user "B.Adhesive")
		(13 "F.Paste" user "Package Geometry/Pastemask Top")
		(15 "B.Paste" user "Package Geometry/Pastemask Bottom")
		(5 "F.SilkS" user "Ref Des/Silkscreen Top")
		(7 "B.SilkS" user "Ref Des/Silkscreen Bottom")
		(1 "F.Mask" user "Board Geometry/Soldermask Top")
		(3 "B.Mask" user "Board Geometry/Soldermask Bottom")
		(17 "Dwgs.User" user "User.Drawings")
		(19 "Cmts.User" user "User.Comments")
		(21 "Eco1.User" user "User.Eco1")
		(23 "Eco2.User" user "User.Eco2")
		(25 "Edge.Cuts" user "Board Geometry/Outline")
		(27 "Margin" user)
		(31 "F.CrtYd" user "Package Geometry/Place Bound Top")
		(29 "B.CrtYd" user "Package Geometry/Place Bound Bottom")
		(35 "F.Fab" user "Ref Des/Assembly Top")
		(33 "B.Fab" user "Ref Des/Assembly Bottom")
	)
	(footprint ""
		(layer "F.Cu")
		(at 385.716272 -66.704464 180)
		(property "Reference" "C547"
			(at 0 0 180)
			(layer "F.SilkS")
			(hide yes)
			(effects
				(font
					(size 1.27 1.27)
				)
			)
		)
		(property "Value" ""
			(at 0 0 180)
			(layer "F.Fab")
			(effects
				(font
					(size 1.27 1.27)
				)
			)
		)
		(duplicate_pad_numbers_are_jumpers no)
		(fp_line
			(start 0.7874 0.4064)
			(end -0.7874 0.4064)
			(stroke
				(width 0.1524)
				(type default)
			)
			(layer "F.SilkS")
		)
		(fp_line
			(start 0.7874 -0.4064)
			(end 0.7874 0.4064)
			(stroke
				(width 0.1524)
				(type default)
			)
			(layer "F.SilkS")
		)
		(fp_line
			(start -0.7874 0.4064)
			(end -0.7874 -0.4064)
			(stroke
				(width 0.1524)
				(type default)
			)
			(layer "F.SilkS")
		)
		(fp_line
			(start -0.7874 -0.4064)
			(end 0.7874 -0.4064)
			(stroke
				(width 0.1524)
				(type default)
			)
			(layer "F.SilkS")
		)
		(fp_line
			(start 0.67945 0.3048)
			(end 0.120396 0.3048)
			(stroke
				(width 0.1)
				(type default)
			)
			(layer "F.Fab")
		)
		(fp_line
			(start 0.67945 -0.3048)
			(end 0.67945 0.3048)
			(stroke
				(width 0.1)
				(type default)
			)
			(layer "F.Fab")
		)
		(fp_line
			(start 0.12065 -0.2794)
			(end 0.12065 -0.3048)
			(stroke
				(width 0.1)
				(type default)
			)
			(layer "F.Fab")
		)
		(fp_line
			(start 0.12065 -0.3048)
			(end 0.67945 -0.3048)
			(stroke
				(width 0.1)
				(type default)
			)
			(layer "F.Fab")
		)
		(fp_line
			(start 0.120396 0.3048)
			(end 0.120396 0.2794)
			(stroke
				(width 0.1)
				(type default)
			)
			(layer "F.Fab")
		)
		(fp_line
			(start 0.120396 0.2794)
			(end -0.12065 0.2794)
			(stroke
				(width 0.1)
				(type default)
			)
			(layer "F.Fab")
		)
		(fp_line
			(start -0.12065 0.3048)
			(end -0.67945 0.3048)
			(stroke
				(width 0.1)
				(type default)
			)
			(layer "F.Fab")
		)
		(fp_line
			(start -0.12065 0.2794)
			(end -0.12065 0.3048)
			(stroke
				(width 0.1)
				(type default)
			)
			(layer "F.Fab")
		)
		(fp_line
			(start -0.12065 -0.2794)
			(end 0.12065 -0.2794)
			(stroke
				(width 0.1)
				(type default)
			)
			(layer "F.Fab")
		)
		(fp_line
			(start -0.12065 -0.305054)
			(end -0.12065 -0.2794)
			(stroke
				(width 0.1)
				(type default)
			)
			(layer "F.Fab")
		)
		(fp_line
			(start -0.67945 0.3048)
			(end -0.67945 -0.305054)
			(stroke
				(width 0.1)
				(type default)
			)
			(layer "F.Fab")
		)
		(fp_line
			(start -0.67945 -0.305054)
			(end -0.12065 -0.305054)
			(stroke
				(width 0.1)
				(type default)
			)
			(layer "F.Fab")
		)
		(pad "1" smd circle
			(at -0.40005 0 180)
			(size 0 0)
			(layers "F.Cu" "F.Mask" "F.Paste")
			(net "P1V05_PCH_AUX")
		)
		(pad "2" smd circle
			(at 0.40005 0 180)
			(size 0 0)
			(layers "F.Cu" "F.Mask" "F.Paste")
			(net "GND")
		)
	)
	(footprint ""
		(layer "F.Cu")
		(at 9.58088 -61.051948)
		(property "Reference" "R3058"
			(at 0 0 0)
			(layer "F.SilkS")
			(hide yes)
			(effects
				(font
					(size 1.27 1.27)
				)
			)
		)
		(property "Value" ""
			(at 0 0 0)
			(layer "F.Fab")
			(effects
				(font
					(size 1.27 1.27)
				)
			)
		)
		(duplicate_pad_numbers_are_jumpers no)
		(fp_line
			(start -0.7874 -0.4064)
			(end 0.7874 -0.4064)
			(stroke
				(width 0.1524)
				(type default)
			)
			(layer "F.SilkS")
		)
		(fp_line
			(start -0.7874 0.4064)
			(end -0.7874 -0.4064)
			(stroke
				(width 0.1524)
				(type default)
			)
			(layer "F.SilkS")
		)
		(fp_line
			(start 0.7874 -0.4064)
			(end 0.7874 0.4064)
			(stroke
				(width 0.1524)
				(type default)
			)
			(layer "F.SilkS")
		)
		(fp_line
			(start 0.7874 0.4064)
			(end -0.7874 0.4064)
			(stroke
				(width 0.1524)
				(type default)
			)
			(layer "F.SilkS")
		)
		(fp_line
			(start -0.67945 -0.305054)
			(end -0.12065 -0.305054)
			(stroke
				(width 0.1)
				(type default)
			)
			(layer "F.Fab")
		)
		(fp_line
			(start -0.67945 0.3048)
			(end -0.67945 -0.305054)
			(stroke
				(width 0.1)
				(type default)
			)
			(layer "F.Fab")
		)
		(fp_line
			(start -0.12065 -0.305054)
			(end -0.12065 -0.2794)
			(stroke
				(width 0.1)
				(type default)
			)
			(layer "F.Fab")
		)
		(fp_line
			(start -0.12065 -0.2794)
			(end 0.12065 -0.2794)
			(stroke
				(width 0.1)
				(type default)
			)
			(layer "F.Fab")
		)
		(fp_line
			(start -0.12065 0.2794)
			(end -0.12065 0.3048)
			(stroke
				(width 0.1)
				(type default)
			)
			(layer "F.Fab")
		)
		(fp_line
			(start -0.12065 0.3048)
			(end -0.67945 0.3048)
			(stroke
				(width 0.1)
				(type default)
			)
			(layer "F.Fab")
		)
		(fp_line
			(start 0.120396 0.2794)
			(end -0.12065 0.2794)
			(stroke
				(width 0.1)
				(type default)
			)
			(layer "F.Fab")
		)
		(fp_line
			(start 0.120396 0.3048)
			(end 0.120396 0.2794)
			(stroke
				(width 0.1)
				(type default)
			)
			(layer "F.Fab")
		)
		(fp_line
			(start 0.12065 -0.3048)
			(end 0.67945 -0.3048)
			(stroke
				(width 0.1)
				(type default)
			)
			(layer "F.Fab")
		)
		(fp_line
			(start 0.12065 -0.2794)
			(end 0.12065 -0.3048)
			(stroke
				(width 0.1)
				(type default)
			)
			(layer "F.Fab")
		)
		(fp_line
			(start 0.67945 -0.3048)
			(end 0.67945 0.3048)
			(stroke
				(width 0.1)
				(type default)
			)
			(layer "F.Fab")
		)
		(fp_line
			(start 0.67945 0.3048)
			(end 0.120396 0.3048)
			(stroke
				(width 0.1)
				(type default)
			)
			(layer "F.Fab")
		)
		(pad "1" smd circle
			(at -0.40005 0)
			(size 0 0)
			(layers "F.Cu" "F.Mask" "F.Paste")
			(net "SMB_SML0_3V3AUX_SCL")
		)
		(pad "2" smd circle
			(at 0.40005 0)
			(size 0 0)
			(layers "F.Cu" "F.Mask" "F.Paste")
			(net "SMB_SML0_ME_SCL")
		)
	)
)
